# S9S_MB_2U (Grand Teton) — schematic netlist excerpt (pin names and nets, part order shuffled) for the footprints in the layout excerpt that follows; sources: Cadence DE-HDL packaged netlist, KiCad conversion of 03242023_DA0F0TMBIJ0_F0T_Motherboard_J_brd_V01_OCP.brd

PR214  Q_RES  1K 1% EMPTY  pkg 0402LF  page 296 : A = PVCCD_HV_CPU1_ISENSE_P ; B = GND
R4770  Q_RES  0 5% CHIP  pkg 0402LF  page 242 : A = HP_LVC3_SCM_HSC_PWRGD_R ; B = HP_LVC3_SCM_HSC_PWRGD
PC1208_P1_3  Q_CAP  22UF 4V 20% X6S  pkg C0805  page 290 : A = PVCCFA_EHV_FIVRA_CPU1 ; B = GND

(kicad_pcb
	(version 20260206)
	(generator "pcbnew")
	(generator_version "10.0")
	(general
		(thickness 1.6)
		(legacy_teardrops no)
	)
	(paper "A4")
	(title_block
		(title "03242023_DA0F0TMBIJ0_F0T_Motherboard_J_brd_V01_OCP.brd")
		(comment 1 "Grand Teton / footprints 4176-4178 of 6105")
	)
	(layers
		(0 "F.Cu" signal "TOP")
		(4 "In1.Cu" signal "GND")
		(6 "In2.Cu" signal "IN1")
		(8 "In3.Cu" signal "GND1")
		(10 "In4.Cu" signal "IN2")
		(12 "In5.Cu" signal "GND2")
		(14 "In6.Cu" signal "IN3")
		(16 "In7.Cu" signal "GND3")
		(18 "In8.Cu" signal "VCC")
		(20 "In9.Cu" signal "VCC1")
		(22 "In10.Cu" signal "GND4")
		(24 "In11.Cu" signal "IN4")
		(26 "In12.Cu" signal "GND5")
		(28 "In13.Cu" signal "IN5")
		(30 "In14.Cu" signal "GND6")
		(32 "In15.Cu" signal "IN6")
		(34 "In16.Cu" signal "GND7")
		(2 "B.Cu" signal "BOTTOM")
		(9 "F.Adhes" user "F.Adhesive")
		(11 "B.Adhes" user "B.Adhesive")
		(13 "F.Paste" user "Package Geometry/Pastemask Top")
		(15 "B.Paste" user "Package Geometry/Pastemask Bottom")
		(5 "F.SilkS" user "Ref Des/Silkscreen Top")
		(7 "B.SilkS" user "Ref Des/Silkscreen Bottom")
		(1 "F.Mask" user "Board Geometry/Soldermask Top")
		(3 "B.Mask" user "Board Geometry/Soldermask Bottom")
		(17 "Dwgs.User" user "User.Drawings")
		(19 "Cmts.User" user "User.Comments")
		(21 "Eco1.User" user "User.Eco1")
		(23 "Eco2.User" user "User.Eco2")
		(25 "Edge.Cuts" user "Board Geometry/Outline")
		(27 "Margin" user)
		(31 "F.CrtYd" user "Package Geometry/Place Bound Top")
		(29 "B.CrtYd" user "Package Geometry/Place Bound Bottom")
		(35 "F.Fab" user "Ref Des/Assembly Top")
		(33 "B.Fab" user "Ref Des/Assembly Bottom")
	)
	(footprint ""
		(layer "B.Cu")
		(at 173.33976 -29.81198 90)
		(property "Reference" "R4770"
			(at 0 0 90)
			(layer "B.SilkS")
			(hide yes)
			(effects
				(font
					(size 1.27 1.27)
				)
				(justify mirror)
			)
		)
		(property "Value" ""
			(at 0 0 90)
			(layer "B.Fab")
			(effects
				(font
					(size 1.27 1.27)
				)
				(justify mirror)
			)
		)
		(duplicate_pad_numbers_are_jumpers no)
		(fp_line
			(start 0.7874 -0.4064)
			(end -0.7874 -0.4064)
			(stroke
				(width 0.1524)
				(type default)
			)
			(layer "B.SilkS")
		)
		(fp_line
			(start -0.7874 -0.4064)
			(end -0.7874 0.4064)
			(stroke
				(width 0.1524)
				(type default)
			)
			(layer "B.SilkS")
		)
		(fp_line
			(start 0.7874 0.4064)
			(end 0.7874 -0.4064)
			(stroke
				(width 0.1524)
				(type default)
			)
			(layer "B.SilkS")
		)
		(fp_line
			(start -0.7874 0.4064)
			(end 0.7874 0.4064)
			(stroke
				(width 0.1524)
				(type default)
			)
			(layer "B.SilkS")
		)
		(fp_line
			(start 0.67945 -0.305054)
			(end 0.12065 -0.305054)
			(stroke
				(width 0.1)
				(type default)
			)
			(layer "B.Fab")
		)
		(fp_line
			(start 0.12065 -0.305054)
			(end 0.12065 -0.2794)
			(stroke
				(width 0.1)
				(type default)
			)
			(layer "B.Fab")
		)
		(fp_line
			(start -0.12065 -0.3048)
			(end -0.67945 -0.3048)
			(stroke
				(width 0.1)
				(type default)
			)
			(layer "B.Fab")
		)
		(fp_line
			(start -0.67945 -0.3048)
			(end -0.67945 0.3048)
			(stroke
				(width 0.1)
				(type default)
			)
			(layer "B.Fab")
		)
		(fp_line
			(start 0.12065 -0.2794)
			(end -0.12065 -0.2794)
			(stroke
				(width 0.1)
				(type default)
			)
			(layer "B.Fab")
		)
		(fp_line
			(start -0.12065 -0.2794)
			(end -0.12065 -0.3048)
			(stroke
				(width 0.1)
				(type default)
			)
			(layer "B.Fab")
		)
		(fp_line
			(start 0.12065 0.2794)
			(end 0.12065 0.3048)
			(stroke
				(width 0.1)
				(type default)
			)
			(layer "B.Fab")
		)
		(fp_line
			(start -0.120396 0.2794)
			(end 0.12065 0.2794)
			(stroke
				(width 0.1)
				(type default)
			)
			(layer "B.Fab")
		)
		(fp_line
			(start 0.67945 0.3048)
			(end 0.67945 -0.305054)
			(stroke
				(width 0.1)
				(type default)
			)
			(layer "B.Fab")
		)
		(fp_line
			(start 0.12065 0.3048)
			(end 0.67945 0.3048)
			(stroke
				(width 0.1)
				(type default)
			)
			(layer "B.Fab")
		)
		(fp_line
			(start -0.120396 0.3048)
			(end -0.120396 0.2794)
			(stroke
				(width 0.1)
				(type default)
			)
			(layer "B.Fab")
		)
		(fp_line
			(start -0.67945 0.3048)
			(end -0.120396 0.3048)
			(stroke
				(width 0.1)
				(type default)
			)
			(layer "B.Fab")
		)
		(pad "1" smd circle
			(at 0.40005 0 270)
			(size 0 0)
			(layers "B.Cu" "B.Mask" "B.Paste")
			(net "HP_LVC3_SCM_HSC_PWRGD_R")
		)
		(pad "2" smd circle
			(at -0.40005 0 270)
			(size 0 0)
			(layers "B.Cu" "B.Mask" "B.Paste")
			(net "HP_LVC3_SCM_HSC_PWRGD")
		)
	)
	(footprint ""
		(layer "B.Cu")
		(at 178.368706 -344.941906 -90)
		(property "Reference" "PC1208_P1_3"
			(at 0 0 90)
			(layer "B.SilkS")
			(hide yes)
			(effects
				(font
					(size 1.27 1.27)
				)
				(justify mirror)
			)
		)
		(property "Value" ""
			(at 0 0 90)
			(layer "B.Fab")
			(effects
				(font
					(size 1.27 1.27)
				)
				(justify mirror)
			)
		)
		(duplicate_pad_numbers_are_jumpers no)
		(fp_line
			(start -1.524 0.762)
			(end 1.524 0.762)
			(stroke
				(width 0.1524)
				(type default)
			)
			(layer "B.SilkS")
		)
		(fp_line
			(start 1.524 0.762)
			(end 1.524 -0.762)
			(stroke
				(width 0.1524)
				(type default)
			)
			(layer "B.SilkS")
		)
		(fp_line
			(start -1.524 -0.762)
			(end -1.524 0.762)
			(stroke
				(width 0.1524)
				(type default)
			)
			(layer "B.SilkS")
		)
		(fp_line
			(start 1.524 -0.762)
			(end -1.524 -0.762)
			(stroke
				(width 0.1524)
				(type default)
			)
			(layer "B.SilkS")
		)
		(fp_line
			(start -1.1049 0.724916)
			(end -1.1049 -0.724916)
			(stroke
				(width 0.1)
				(type default)
			)
			(layer "B.Fab")
		)
		(fp_line
			(start 1.1049 0.724916)
			(end -1.1049 0.724916)
			(stroke
				(width 0.1)
				(type default)
			)
			(layer "B.Fab")
		)
		(fp_line
			(start -1.1049 -0.724916)
			(end 1.1049 -0.724916)
			(stroke
				(width 0.1)
				(type default)
			)
			(layer "B.Fab")
		)
		(fp_line
			(start 1.1049 -0.724916)
			(end 1.1049 0.724916)
			(stroke
				(width 0.1)
				(type default)
			)
			(layer "B.Fab")
		)
		(pad "1" smd rect
			(at 0.889 0 270)
			(size 1.016 1.27)
			(layers "B.Cu" "B.Mask" "B.Paste")
			(net "PVCCFA_EHV_FIVRA_CPU1")
		)
		(pad "2" smd rect
			(at -0.889 0 270)
			(size 1.016 1.27)
			(layers "B.Cu" "B.Mask" "B.Paste")
			(net "GND")
		)
	)
	(footprint ""
		(layer "B.Cu")
		(at 29.577538 -165.540436)
		(property "Reference" "PR214"
			(at 0 0 0)
			(layer "B.SilkS")
			(hide yes)
			(effects
				(font
					(size 1.27 1.27)
				)
				(justify mirror)
			)
		)
		(property "Value" ""
			(at 0 0 0)
			(layer "B.Fab")
			(effects
				(font
					(size 1.27 1.27)
				)
				(justify mirror)
			)
		)
		(duplicate_pad_numbers_are_jumpers no)
		(fp_line
			(start -0.7874 -0.4064)
			(end -0.7874 0.4064)
			(stroke
				(width 0.1524)
				(type default)
			)
			(layer "B.SilkS")
		)
		(fp_line
			(start -0.7874 0.4064)
			(end 0.7874 0.4064)
			(stroke
				(width 0.1524)
				(type default)
			)
			(layer "B.SilkS")
		)
		(fp_line
			(start 0.7874 -0.4064)
			(end -0.7874 -0.4064)
			(stroke
				(width 0.1524)
				(type default)
			)
			(layer "B.SilkS")
		)
		(fp_line
			(start 0.7874 0.4064)
			(end 0.7874 -0.4064)
			(stroke
				(width 0.1524)
				(type default)
			)
			(layer "B.SilkS")
		)
		(fp_line
			(start -0.67945 -0.3048)
			(end -0.67945 0.3048)
			(stroke
				(width 0.1)
				(type default)
			)
			(layer "B.Fab")
		)
		(fp_line
			(start -0.67945 0.3048)
			(end -0.120396 0.3048)
			(stroke
				(width 0.1)
				(type default)
			)
			(layer "B.Fab")
		)
		(fp_line
			(start -0.12065 -0.3048)
			(end -0.67945 -0.3048)
			(stroke
				(width 0.1)
				(type default)
			)
			(layer "B.Fab")
		)
		(fp_line
			(start -0.12065 -0.2794)
			(end -0.12065 -0.3048)
			(stroke
				(width 0.1)
				(type default)
			)
			(layer "B.Fab")
		)
		(fp_line
			(start -0.120396 0.2794)
			(end 0.12065 0.2794)
			(stroke
				(width 0.1)
				(type default)
			)
			(layer "B.Fab")
		)
		(fp_line
			(start -0.120396 0.3048)
			(end -0.120396 0.2794)
			(stroke
				(width 0.1)
				(type default)
			)
			(layer "B.Fab")
		)
		(fp_line
			(start 0.12065 -0.305054)
			(end 0.12065 -0.2794)
			(stroke
				(width 0.1)
				(type default)
			)
			(layer "B.Fab")
		)
		(fp_line
			(start 0.12065 -0.2794)
			(end -0.12065 -0.2794)
			(stroke
				(width 0.1)
				(type default)
			)
			(layer "B.Fab")
		)
		(fp_line
			(start 0.12065 0.2794)
			(end 0.12065 0.3048)
			(stroke
				(width 0.1)
				(type default)
			)
			(layer "B.Fab")
		)
		(fp_line
			(start 0.12065 0.3048)
			(end 0.67945 0.3048)
			(stroke
				(width 0.1)
				(type default)
			)
			(layer "B.Fab")
		)
		(fp_line
			(start 0.67945 -0.305054)
			(end 0.12065 -0.305054)
			(stroke
				(width 0.1)
				(type default)
			)
			(layer "B.Fab")
		)
		(fp_line
			(start 0.67945 0.3048)
			(end 0.67945 -0.305054)
			(stroke
				(width 0.1)
				(type default)
			)
			(layer "B.Fab")
		)
		(pad "1" smd circle
			(at 0.40005 0 180)
			(size 0 0)
			(layers "B.Cu" "B.Mask" "B.Paste")
			(net "PVCCD_HV_CPU1_ISENSE_P")
		)
		(pad "2" smd circle
			(at -0.40005 0 180)
			(size 0 0)
			(layers "B.Cu" "B.Mask" "B.Paste")
			(net "GND")
		)
	)
)
